# BASEBOARD_FAB2 (Tioga Pass) — schematic netlist excerpt (pin names and nets, part order shuffled) for the footprints in the layout excerpt that follows; sources: Cadence DE-HDL packaged netlist, KiCad conversion of Wiwynn_Tioga_Pass_MB.brd

J4G3  SCONN288_H44441004  SCONN  pkg PIP  page 47
  \12v\(1)  = P12V_NVDIMM_ABC
  VSS(93)  = GND
  DQ(4)  = M_C_DQ<5>
  VSS(92)  = GND
  DQ(0)  = M_C_DQ<1>
  VSS(91)  = GND
  DQS9P  = M_C_DQS_DP<9>
  DQS9N  = M_C_DQS_DN<9>
  VSS(90)  = GND
  DQ(6)  = M_C_DQ<7>
  VSS(89)  = GND
  DQ(2)  = M_C_DQ<3>
  VSS(88)  = GND
  DQ(12)  = M_C_DQ<13>
  VSS(87)  = GND
  DQ(8)  = M_C_DQ<9>
  VSS(86)  = GND
  DQS10P  = M_C_DQS_DP<10>
  DQS10N  = M_C_DQS_DN<10>
  VSS(85)  = GND
  DQ(14)  = M_C_DQ<15>
  VSS(84)  = GND
  DQ(10)  = M_C_DQ<11>
  VSS(83)  = GND
  DQ(20)  = M_C_DQ<21>
  VSS(82)  = GND
  DQ(16)  = M_C_DQ<17>
  VSS(81)  = GND
  DQS11P  = M_C_DQS_DP<11>
  DQS11N  = M_C_DQS_DN<11>
  VSS(80)  = GND
  DQ(22)  = M_C_DQ<23>
  VSS(79)  = GND
  DQ(18)  = M_C_DQ<19>
  VSS(78)  = GND
  DQ(28)  = M_C_DQ<29>
  VSS(77)  = GND
  DQ(24)  = M_C_DQ<25>
  VSS(76)  = GND
  DQS12P  = M_C_DQS_DP<12>
  DQS12N  = M_C_DQS_DN<12>
  VSS(75)  = GND
  DQ(30)  = M_C_DQ<31>
  VSS(74)  = GND
  DQ(26)  = M_C_DQ<27>
  VSS(73)  = GND
  CB(4)  = M_C_ECC<5>
  VSS(72)  = GND
  CB(0)  = M_C_ECC<1>
  VSS(71)  = GND
  DQS17P  = M_C_DQS_DP<17>
  DQS17N  = M_C_DQS_DN<17>
  VSS(70)  = GND
  CB(6)  = M_C_ECC<7>
  VSS(69)  = GND
  CB(2)  = M_C_ECC<3>
  VSS(68)  = GND
  RESET_N  = M_ABC_RST_N
  VDD(25)  = PVDDQ_ABC
  CKE(0)  = M_C_CKE<0>
  VDD(24)  = PVDDQ_ABC
  ACT_N  = M_C_ACT_N
  BG(0)  = M_C_BG<0>
  VDD(23)  = PVDDQ_ABC
  A12  = M_C_MA<12>
  A9  = M_C_MA<9>
  VDD(22)  = PVDDQ_ABC
  A8  = M_C_MA<8>
  A6  = M_C_MA<6>
  VDD(21)  = PVDDQ_ABC
  A3  = M_C_MA<3>
  A1  = M_C_MA<1>
  VDD(20)  = PVDDQ_ABC
  CK0P  = M_C_CLK_DP<0>
  CK0N  = M_C_CLK_DN<0>
  VDD(19)  = PVDDQ_ABC
  VTT(1)  = PVTT_ABC
  EVENT_N  = FM_DIMM_EVENT_COD_N
  A0  = M_C_MA<0>
  VDD(18)  = PVDDQ_ABC
  BA(0)  = M_C_BA<0>
  A16_RAS_N  = M_C_MA<16>
  VDD(17)  = PVDDQ_ABC
  S0_N  = M_C_CS_N<0>
  VDD(16)  = PVDDQ_ABC
  A15_CAS_N  = M_C_MA<15>
  ODT(0)  = M_C_ODT<0>
  VDD(15)  = PVDDQ_ABC
  S1_N  = M_C_CS_N<1>
  VDD(14)  = PVDDQ_ABC
  ODT(1)  = M_C_ODT<1>
  VDD(13)  = PVDDQ_ABC
  S2_N_C(0)  = M_C_CS_N<2>
  VSS(67)  = GND
  DQ(36)  = M_C_DQ<37>
  VSS(66)  = GND
  DQ(32)  = M_C_DQ<33>
  VSS(65)  = GND
  DQS13P  = M_C_DQS_DP<13>
  DQS13N  = M_C_DQS_DN<13>
  VSS(64)  = GND
  DQ(38)  = M_C_DQ<39>
  VSS(63)  = GND
  DQ(34)  = M_C_DQ<35>
  VSS(62)  = GND
  DQ(44)  = M_C_DQ<45>
  VSS(61)  = GND
  DQ(40)  = M_C_DQ<41>
  VSS(60)  = GND
  DQS14P  = M_C_DQS_DP<14>
  DQS14N  = M_C_DQS_DN<14>
  VSS(59)  = GND
  DQ(46)  = M_C_DQ<47>
  VSS(58)  = GND
  DQ(42)  = M_C_DQ<43>
  VSS(57)  = GND
  DQ(52)  = M_C_DQ<53>
  VSS(56)  = GND
  DQ(48)  = M_C_DQ<49>
  VSS(55)  = GND
  DQS15P  = M_C_DQS_DP<15>
  DQS15N  = M_C_DQS_DN<15>
  VSS(54)  = GND
  DQ(54)  = M_C_DQ<55>
  VSS(53)  = GND
  DQ(50)  = M_C_DQ<51>
  VSS(52)  = GND
  DQ(60)  = M_C_DQ<61>
  VSS(51)  = GND
  DQ(56)  = M_C_DQ<57>
  VSS(50)  = GND
  DQS16P  = M_C_DQS_DP<16>
  DQS16N  = M_C_DQS_DN<16>
  VSS(49)  = GND
  DQ(62)  = M_C_DQ<63>
  VSS(48)  = GND
  DQ(58)  = M_C_DQ<59>
  VSS(47)  = GND
  SA(0)  = GND
  SA(1)  = GND
  SCL  = SMB_DDR_ABC_VPP_SCL
  VPP(4)  = PVPP_ABC
  VPP(3)  = PVPP_ABC
  RFU(2)  = TP_CH_C_DIMM_C0_RFU_2
  \12v\(0)  = P12V_NVDIMM_ABC
  VREFCA  = M_C_VREF
  VSS(46)  = GND
  DQ(5)  = M_C_DQ<4>
  VSS(45)  = GND
  DQ(1)  = M_C_DQ<0>
  VSS(44)  = GND
  DQS0N  = M_C_DQS_DN<0>
  DQS0P  = M_C_DQS_DP<0>
  VSS(43)  = GND
  DQ(7)  = M_C_DQ<6>
  VSS(42)  = GND
  DQ(3)  = M_C_DQ<2>
  VSS(41)  = GND
  DQ(13)  = M_C_DQ<12>
  VSS(40)  = GND
  DQ(9)  = M_C_DQ<8>
  VSS(39)  = GND
  DQS1N  = M_C_DQS_DN<1>
  DQS1P  = M_C_DQS_DP<1>
  VSS(38)  = GND
  DQ(15)  = M_C_DQ<14>
  VSS(37)  = GND
  DQ(11)  = M_C_DQ<10>
  VSS(36)  = GND
  DQ(21)  = M_C_DQ<20>
  VSS(35)  = GND
  DQ(17)  = M_C_DQ<16>
  VSS(34)  = GND
  DQS2N  = M_C_DQS_DN<2>
  DQS2P  = M_C_DQS_DP<2>
  VSS(33)  = GND
  DQ(23)  = M_C_DQ<22>
  VSS(32)  = GND
  DQ(19)  = M_C_DQ<18>
  VSS(31)  = GND
  DQ(29)  = M_C_DQ<28>
  VSS(30)  = GND
  DQ(25)  = M_C_DQ<24>
  VSS(29)  = GND
  DQS3N  = M_C_DQS_DN<3>
  DQS3P  = M_C_DQS_DP<3>
  VSS(28)  = GND
  DQ(31)  = M_C_DQ<30>
  VSS(27)  = GND
  DQ(27)  = M_C_DQ<26>
  VSS(26)  = GND
  CB(5)  = M_C_ECC<4>
  VSS(25)  = GND
  CB(1)  = M_C_ECC<0>
  VSS(24)  = GND
  DQS8N  = M_C_DQS_DN<8>
  DQS8P  = M_C_DQS_DP<8>
  VSS(23)  = GND
  CB(7)  = M_C_ECC<6>
  VSS(22)  = GND
  CB(3)  = M_C_ECC<2>
  VSS(21)  = GND
  CKE(1)  = M_C_CKE<1>
  VDD(12)  = PVDDQ_ABC
  RFU(0)  = TP_CH_C_DIMM_C0_RFU_0
  VDD(11)  = PVDDQ_ABC
  BG(1)  = M_C_BG<1>
  ALERT_N  = M_C_ALERT_N
  VDD(10)  = PVDDQ_ABC
  A11  = M_C_MA<11>
  A7  = M_C_MA<7>
  VDD(9)  = PVDDQ_ABC
  A5  = M_C_MA<5>
  A4  = M_C_MA<4>
  VDD(8)  = PVDDQ_ABC
  A2  = M_C_MA<2>
  VDD(7)  = PVDDQ_ABC
  CK1P  = M_C_CLK_DP<1>
  CK1N  = M_C_CLK_DN<1>
  VDD(6)  = PVDDQ_ABC
  VTT(0)  = PVTT_ABC
  PAR  = M_C_PAR
  VDD(5)  = PVDDQ_ABC
  BA(1)  = M_C_BA<1>
  A10  = M_C_MA<10>
  VDD(4)  = PVDDQ_ABC
  RFU(1)  = TP_CH_C_DIMM_C0_RFU_1
  A14_WE_N  = M_C_MA<14>
  VDD(3)  = PVDDQ_ABC
  SAVE_N_NC  = FM_ADR_COMPLETE_ABC_N
  VDD(2)  = PVDDQ_ABC
  A13  = M_C_MA<13>
  VDD(1)  = PVDDQ_ABC
  A17  = M_C_MA<17>
  C(2)  = M_C_C<2>
  VDD(0)  = PVDDQ_ABC
  S3_N_C(1)  = M_C_CS_N<3>
  SA(2)  = PVPP_ABC
  VSS(20)  = GND
  DQ(37)  = M_C_DQ<36>
  VSS(19)  = GND
  DQ(33)  = M_C_DQ<32>
  VSS(18)  = GND
  DQS4N  = M_C_DQS_DN<4>
  DQS4P  = M_C_DQS_DP<4>
  VSS(17)  = GND
  DQ(39)  = M_C_DQ<38>
  VSS(16)  = GND
  DQ(35)  = M_C_DQ<34>
  VSS(15)  = GND
  DQ(45)  = M_C_DQ<44>
  VSS(14)  = GND
  DQ(41)  = M_C_DQ<40>
  VSS(13)  = GND
  DQS5N  = M_C_DQS_DN<5>
  DQS5P  = M_C_DQS_DP<5>
  VSS(12)  = GND
  DQ(47)  = M_C_DQ<46>
  VSS(11)  = GND
  DQ(43)  = M_C_DQ<42>
  VSS(10)  = GND
  DQ(53)  = M_C_DQ<52>
  VSS(9)  = GND
  DQ(49)  = M_C_DQ<48>
  VSS(8)  = GND
  DQS6N  = M_C_DQS_DN<6>
  DQS6P  = M_C_DQS_DP<6>
  VSS(7)  = GND
  DQ(55)  = M_C_DQ<54>
  VSS(6)  = GND
  DQ(51)  = M_C_DQ<50>
  VSS(5)  = GND
  DQ(61)  = M_C_DQ<60>
  VSS(4)  = GND
  DQ(57)  = M_C_DQ<56>
  VSS(3)  = GND
  DQS7N  = M_C_DQS_DN<7>
  DQS7P  = M_C_DQS_DP<7>
  VSS(2)  = GND
  DQ(63)  = M_C_DQ<62>
  VSS(1)  = GND
  DQ(59)  = M_C_DQ<58>
  VSS(0)  = GND
  VDDSPD  = PVPP_ABC
  SDA  = SMB_DDR_ABC_VPP_SDA
  VPP(1)  = PVPP_ABC
  VPP(0)  = PVPP_ABC
  VPP(2)  = PVPP_ABC

(kicad_pcb
	(version 20260206)
	(generator "pcbnew")
	(generator_version "10.0")
	(general
		(thickness 1.6)
		(legacy_teardrops no)
	)
	(paper "A4")
	(title_block
		(title "Wiwynn_Tioga_Pass_MB.brd")
		(comment 1 "Tioga Pass / footprint 1441 of 4770 (J4G3), pads 52-101 of 291")
	)
	(layers
		(0 "F.Cu" signal "TOP")
		(4 "In1.Cu" signal "L2GND")
		(6 "In2.Cu" signal "L3")
		(8 "In3.Cu" signal "L4GND")
		(10 "In4.Cu" signal "L5")
		(12 "In5.Cu" signal "L6GND")
		(14 "In6.Cu" signal "L7VCC")
		(16 "In7.Cu" signal "L8VCC")
		(18 "In8.Cu" signal "L9GND")
		(20 "In9.Cu" signal "L10")
		(22 "In10.Cu" signal "L11GND")
		(24 "In11.Cu" signal "L12")
		(26 "In12.Cu" signal "L13GND")
		(2 "B.Cu" signal "BOTTOM")
		(9 "F.Adhes" user "F.Adhesive")
		(11 "B.Adhes" user "B.Adhesive")
		(13 "F.Paste" user "Package Geometry/Pastemask Top")
		(15 "B.Paste" user "Package Geometry/Pastemask Bottom")
		(5 "F.SilkS" user "Ref Des/Silkscreen Top")
		(7 "B.SilkS" user "Ref Des/Silkscreen Bottom")
		(1 "F.Mask" user "Board Geometry/Soldermask Top")
		(3 "B.Mask" user "Board Geometry/Soldermask Bottom")
		(17 "Dwgs.User" user "User.Drawings")
		(19 "Cmts.User" user "User.Comments")
		(21 "Eco1.User" user "User.Eco1")
		(23 "Eco2.User" user "User.Eco2")
		(25 "Edge.Cuts" user "Board Geometry/Outline")
		(27 "Margin" user)
		(31 "F.CrtYd" user "Package Geometry/Place Bound Top")
		(29 "B.CrtYd" user "Package Geometry/Place Bound Bottom")
		(35 "F.Fab" user "Ref Des/Assembly Top")
		(33 "B.Fab" user "Ref Des/Assembly Bottom")
	)
	(footprint ""
		(layer "F.Cu")
		(at 194.700398 3.778758 90)
		(property "Reference" "J4G3"
			(at 6.800088 37.20211 0)
			(unlocked yes)
			(layer "F.SilkS")
			(effects
				(font
					(size 0.7874 0.5842)
					(thickness 0.1524)
				)
				(justify left)
			)
		)
		(property "Value" ""
			(at 0 0 90)
			(layer "F.Fab")
			(effects
				(font
					(size 1.27 1.27)
				)
			)
		)
		(duplicate_pad_numbers_are_jumpers no)
		(pad "49" smd rect
			(at 0 40.80002 90)
			(size 1.8034 0.508)
			(layers "F.Cu" "F.Mask" "F.Paste")
			(net "M_C_ECC<1>")
		)
		(pad "50" smd rect
			(at 0 41.649904 90)
			(size 1.8034 0.508)
			(layers "F.Cu" "F.Mask" "F.Paste")
			(net "GND")
		)
		(pad "51" smd rect
			(at 0 42.500042 90)
			(size 1.8034 0.508)
			(layers "F.Cu" "F.Mask" "F.Paste")
			(net "M_C_DQS_DP<17>")
		)
		(pad "52" smd rect
			(at 0 43.349926 90)
			(size 1.8034 0.508)
			(layers "F.Cu" "F.Mask" "F.Paste")
			(net "M_C_DQS_DN<17>")
		)
		(pad "53" smd rect
			(at 0 44.200064 90)
			(size 1.8034 0.508)
			(layers "F.Cu" "F.Mask" "F.Paste")
			(net "GND")
		)
		(pad "54" smd rect
			(at 0 45.049948 90)
			(size 1.8034 0.508)
			(layers "F.Cu" "F.Mask" "F.Paste")
			(net "M_C_ECC<7>")
		)
		(pad "55" smd rect
			(at 0 45.900086 90)
			(size 1.8034 0.508)
			(layers "F.Cu" "F.Mask" "F.Paste")
			(net "GND")
		)
		(pad "56" smd rect
			(at 0 46.74997 90)
			(size 1.8034 0.508)
			(layers "F.Cu" "F.Mask" "F.Paste")
			(net "M_C_ECC<3>")
		)
		(pad "57" smd rect
			(at 0 47.600108 90)
			(size 1.8034 0.508)
			(layers "F.Cu" "F.Mask" "F.Paste")
			(net "GND")
		)
		(pad "58" smd rect
			(at 0 48.449992 90)
			(size 1.8034 0.508)
			(layers "F.Cu" "F.Mask" "F.Paste")
			(net "M_ABC_RST_N")
		)
		(pad "59" smd rect
			(at 0 49.299876 90)
			(size 1.8034 0.508)
			(layers "F.Cu" "F.Mask" "F.Paste")
			(net "PVDDQ_ABC")
		)
		(pad "60" smd rect
			(at 0 50.150014 90)
			(size 1.8034 0.508)
			(layers "F.Cu" "F.Mask" "F.Paste")
			(net "M_C_CKE<0>")
		)
		(pad "61" smd rect
			(at 0 50.999898 90)
			(size 1.8034 0.508)
			(layers "F.Cu" "F.Mask" "F.Paste")
			(net "PVDDQ_ABC")
		)
		(pad "62" smd rect
			(at 0 51.850036 90)
			(size 1.8034 0.508)
			(layers "F.Cu" "F.Mask" "F.Paste")
			(net "M_C_ACT_N")
		)
		(pad "63" smd rect
			(at 0 52.69992 90)
			(size 1.8034 0.508)
			(layers "F.Cu" "F.Mask" "F.Paste")
			(net "M_C_BG<0>")
		)
		(pad "64" smd rect
			(at 0 53.550058 90)
			(size 1.8034 0.508)
			(layers "F.Cu" "F.Mask" "F.Paste")
			(net "PVDDQ_ABC")
		)
		(pad "65" smd rect
			(at 0 54.399942 90)
			(size 1.8034 0.508)
			(layers "F.Cu" "F.Mask" "F.Paste")
			(net "M_C_MA<12>")
		)
		(pad "66" smd rect
			(at 0 55.25008 90)
			(size 1.8034 0.508)
			(layers "F.Cu" "F.Mask" "F.Paste")
			(net "M_C_MA<9>")
		)
		(pad "67" smd rect
			(at 0 56.099964 90)
			(size 1.8034 0.508)
			(layers "F.Cu" "F.Mask" "F.Paste")
			(net "PVDDQ_ABC")
		)
		(pad "68" smd rect
			(at 0 56.950102 90)
			(size 1.8034 0.508)
			(layers "F.Cu" "F.Mask" "F.Paste")
			(net "M_C_MA<8>")
		)
		(pad "69" smd rect
			(at 0 57.799986 90)
			(size 1.8034 0.508)
			(layers "F.Cu" "F.Mask" "F.Paste")
			(net "M_C_MA<6>")
		)
		(pad "70" smd rect
			(at 0 58.650124 90)
			(size 1.8034 0.508)
			(layers "F.Cu" "F.Mask" "F.Paste")
			(net "PVDDQ_ABC")
		)
		(pad "71" smd rect
			(at 0 59.500008 90)
			(size 1.8034 0.508)
			(layers "F.Cu" "F.Mask" "F.Paste")
			(net "M_C_MA<3>")
		)
		(pad "72" smd rect
			(at 0 60.349892 90)
			(size 1.8034 0.508)
			(layers "F.Cu" "F.Mask" "F.Paste")
			(net "M_C_MA<1>")
		)
		(pad "73" smd rect
			(at 0 61.20003 90)
			(size 1.8034 0.508)
			(layers "F.Cu" "F.Mask" "F.Paste")
			(net "PVDDQ_ABC")
		)
		(pad "74" smd rect
			(at 0 62.049914 90)
			(size 1.8034 0.508)
			(layers "F.Cu" "F.Mask" "F.Paste")
			(net "M_C_CLK_DP<0>")
		)
		(pad "75" smd rect
			(at 0 62.900052 90)
			(size 1.8034 0.508)
			(layers "F.Cu" "F.Mask" "F.Paste")
			(net "M_C_CLK_DN<0>")
		)
		(pad "76" smd rect
			(at 0 63.749936 90)
			(size 1.8034 0.508)
			(layers "F.Cu" "F.Mask" "F.Paste")
			(net "PVDDQ_ABC")
		)
		(pad "77" smd rect
			(at 0 64.600074 90)
			(size 1.8034 0.508)
			(layers "F.Cu" "F.Mask" "F.Paste")
			(net "PVTT_ABC")
		)
		(pad "78" smd rect
			(at 0 70.550024 90)
			(size 1.8034 0.508)
			(layers "F.Cu" "F.Mask" "F.Paste")
			(net "FM_DIMM_EVENT_COD_N")
		)
		(pad "79" smd rect
			(at 0 71.399908 90)
			(size 1.8034 0.508)
			(layers "F.Cu" "F.Mask" "F.Paste")
			(net "M_C_MA<0>")
		)
		(pad "80" smd rect
			(at 0 72.250046 90)
			(size 1.8034 0.508)
			(layers "F.Cu" "F.Mask" "F.Paste")
			(net "PVDDQ_ABC")
		)
		(pad "81" smd rect
			(at 0 73.09993 90)
			(size 1.8034 0.508)
			(layers "F.Cu" "F.Mask" "F.Paste")
			(net "M_C_BA<0>")
		)
		(pad "82" smd rect
			(at 0 73.950068 90)
			(size 1.8034 0.508)
			(layers "F.Cu" "F.Mask" "F.Paste")
			(net "M_C_MA<16>")
		)
		(pad "83" smd rect
			(at 0 74.799952 90)
			(size 1.8034 0.508)
			(layers "F.Cu" "F.Mask" "F.Paste")
			(net "PVDDQ_ABC")
		)
		(pad "84" smd rect
			(at 0 75.65009 90)
			(size 1.8034 0.508)
			(layers "F.Cu" "F.Mask" "F.Paste")
			(net "M_C_CS_N<0>")
		)
		(pad "85" smd rect
			(at 0 76.499974 90)
			(size 1.8034 0.508)
			(layers "F.Cu" "F.Mask" "F.Paste")
			(net "PVDDQ_ABC")
		)
		(pad "86" smd rect
			(at 0 77.350112 90)
			(size 1.8034 0.508)
			(layers "F.Cu" "F.Mask" "F.Paste")
			(net "M_C_MA<15>")
		)
		(pad "87" smd rect
			(at 0 78.199996 90)
			(size 1.8034 0.508)
			(layers "F.Cu" "F.Mask" "F.Paste")
			(net "M_C_ODT<0>")
		)
		(pad "88" smd rect
			(at 0 79.04988 90)
			(size 1.8034 0.508)
			(layers "F.Cu" "F.Mask" "F.Paste")
			(net "PVDDQ_ABC")
		)
		(pad "89" smd rect
			(at 0 79.900018 90)
			(size 1.8034 0.508)
			(layers "F.Cu" "F.Mask" "F.Paste")
			(net "M_C_CS_N<1>")
		)
		(pad "90" smd rect
			(at 0 80.749902 90)
			(size 1.8034 0.508)
			(layers "F.Cu" "F.Mask" "F.Paste")
			(net "PVDDQ_ABC")
		)
		(pad "91" smd rect
			(at 0 81.60004 90)
			(size 1.8034 0.508)
			(layers "F.Cu" "F.Mask" "F.Paste")
			(net "M_C_ODT<1>")
		)
		(pad "92" smd rect
			(at 0 82.449924 90)
			(size 1.8034 0.508)
			(layers "F.Cu" "F.Mask" "F.Paste")
			(net "PVDDQ_ABC")
		)
		(pad "93" smd rect
			(at 0 83.300062 90)
			(size 1.8034 0.508)
			(layers "F.Cu" "F.Mask" "F.Paste")
			(net "M_C_CS_N<2>")
		)
		(pad "94" smd rect
			(at 0 84.149946 90)
			(size 1.8034 0.508)
			(layers "F.Cu" "F.Mask" "F.Paste")
			(net "GND")
		)
		(pad "95" smd rect
			(at 0 85.000084 90)
			(size 1.8034 0.508)
			(layers "F.Cu" "F.Mask" "F.Paste")
			(net "M_C_DQ<37>")
		)
		(pad "96" smd rect
			(at 0 85.849968 90)
			(size 1.8034 0.508)
			(layers "F.Cu" "F.Mask" "F.Paste")
			(net "GND")
		)
		(pad "97" smd rect
			(at 0 86.700106 90)
			(size 1.8034 0.508)
			(layers "F.Cu" "F.Mask" "F.Paste")
			(net "M_C_DQ<33>")
		)
		(pad "98" smd rect
			(at 0 87.54999 90)
			(size 1.8034 0.508)
			(layers "F.Cu" "F.Mask" "F.Paste")
			(net "GND")
		)
	)
)
